# S9S_MB_2U (Grand Teton) — schematic netlist excerpt (pin names and nets, part order shuffled) for the footprints in the layout excerpt that follows; sources: Cadence DE-HDL packaged netlist, KiCad conversion of 03242023_DA0F0TMBIJ0_F0T_Motherboard_J_brd_V01_OCP.brd

R239  Q_RES  0 5% CHIP  pkg 0402LF  page 121 : A = H_CPU0_PROCHOT_LVC1_R_N ; B = H_CPU0_PROCHOT_LVC1_N
R880  Q_RES  33.2 1% CHIP  pkg 0402LF  page 114 : A = PWRGD_CHB_CPU0_DIMM2 ; B = PWRGD_FAIL_CPU0_AB

(kicad_pcb
	(version 20260206)
	(generator "pcbnew")
	(generator_version "10.0")
	(general
		(thickness 1.6)
		(legacy_teardrops no)
	)
	(paper "A4")
	(title_block
		(title "03242023_DA0F0TMBIJ0_F0T_Motherboard_J_brd_V01_OCP.brd")
		(comment 1 "Grand Teton / footprints 5555-5556 of 6105")
	)
	(layers
		(0 "F.Cu" signal "TOP")
		(4 "In1.Cu" signal "GND")
		(6 "In2.Cu" signal "IN1")
		(8 "In3.Cu" signal "GND1")
		(10 "In4.Cu" signal "IN2")
		(12 "In5.Cu" signal "GND2")
		(14 "In6.Cu" signal "IN3")
		(16 "In7.Cu" signal "GND3")
		(18 "In8.Cu" signal "VCC")
		(20 "In9.Cu" signal "VCC1")
		(22 "In10.Cu" signal "GND4")
		(24 "In11.Cu" signal "IN4")
		(26 "In12.Cu" signal "GND5")
		(28 "In13.Cu" signal "IN5")
		(30 "In14.Cu" signal "GND6")
		(32 "In15.Cu" signal "IN6")
		(34 "In16.Cu" signal "GND7")
		(2 "B.Cu" signal "BOTTOM")
		(9 "F.Adhes" user "F.Adhesive")
		(11 "B.Adhes" user "B.Adhesive")
		(13 "F.Paste" user "Package Geometry/Pastemask Top")
		(15 "B.Paste" user "Package Geometry/Pastemask Bottom")
		(5 "F.SilkS" user "Ref Des/Silkscreen Top")
		(7 "B.SilkS" user "Ref Des/Silkscreen Bottom")
		(1 "F.Mask" user "Board Geometry/Soldermask Top")
		(3 "B.Mask" user "Board Geometry/Soldermask Bottom")
		(17 "Dwgs.User" user "User.Drawings")
		(19 "Cmts.User" user "User.Comments")
		(21 "Eco1.User" user "User.Eco1")
		(23 "Eco2.User" user "User.Eco2")
		(25 "Edge.Cuts" user "Board Geometry/Outline")
		(27 "Margin" user)
		(31 "F.CrtYd" user "Package Geometry/Place Bound Top")
		(29 "B.CrtYd" user "Package Geometry/Place Bound Bottom")
		(35 "F.Fab" user "Ref Des/Assembly Top")
		(33 "B.Fab" user "Ref Des/Assembly Bottom")
	)
	(footprint ""
		(layer "B.Cu")
		(at 297.852846 -318.988948 90)
		(property "Reference" "R880"
			(at 0 0 90)
			(layer "B.SilkS")
			(hide yes)
			(effects
				(font
					(size 1.27 1.27)
				)
				(justify mirror)
			)
		)
		(property "Value" ""
			(at 0 0 90)
			(layer "B.Fab")
			(effects
				(font
					(size 1.27 1.27)
				)
				(justify mirror)
			)
		)
		(duplicate_pad_numbers_are_jumpers no)
		(fp_line
			(start 0.7874 -0.4064)
			(end -0.7874 -0.4064)
			(stroke
				(width 0.1524)
				(type default)
			)
			(layer "B.SilkS")
		)
		(fp_line
			(start -0.7874 -0.4064)
			(end -0.7874 0.4064)
			(stroke
				(width 0.1524)
				(type default)
			)
			(layer "B.SilkS")
		)
		(fp_line
			(start 0.7874 0.4064)
			(end 0.7874 -0.4064)
			(stroke
				(width 0.1524)
				(type default)
			)
			(layer "B.SilkS")
		)
		(fp_line
			(start -0.7874 0.4064)
			(end 0.7874 0.4064)
			(stroke
				(width 0.1524)
				(type default)
			)
			(layer "B.SilkS")
		)
		(fp_line
			(start 0.67945 -0.305054)
			(end 0.12065 -0.305054)
			(stroke
				(width 0.1)
				(type default)
			)
			(layer "B.Fab")
		)
		(fp_line
			(start 0.12065 -0.305054)
			(end 0.12065 -0.2794)
			(stroke
				(width 0.1)
				(type default)
			)
			(layer "B.Fab")
		)
		(fp_line
			(start -0.12065 -0.3048)
			(end -0.67945 -0.3048)
			(stroke
				(width 0.1)
				(type default)
			)
			(layer "B.Fab")
		)
		(fp_line
			(start -0.67945 -0.3048)
			(end -0.67945 0.3048)
			(stroke
				(width 0.1)
				(type default)
			)
			(layer "B.Fab")
		)
		(fp_line
			(start 0.12065 -0.2794)
			(end -0.12065 -0.2794)
			(stroke
				(width 0.1)
				(type default)
			)
			(layer "B.Fab")
		)
		(fp_line
			(start -0.12065 -0.2794)
			(end -0.12065 -0.3048)
			(stroke
				(width 0.1)
				(type default)
			)
			(layer "B.Fab")
		)
		(fp_line
			(start 0.12065 0.2794)
			(end 0.12065 0.3048)
			(stroke
				(width 0.1)
				(type default)
			)
			(layer "B.Fab")
		)
		(fp_line
			(start -0.120396 0.2794)
			(end 0.12065 0.2794)
			(stroke
				(width 0.1)
				(type default)
			)
			(layer "B.Fab")
		)
		(fp_line
			(start 0.67945 0.3048)
			(end 0.67945 -0.305054)
			(stroke
				(width 0.1)
				(type default)
			)
			(layer "B.Fab")
		)
		(fp_line
			(start 0.12065 0.3048)
			(end 0.67945 0.3048)
			(stroke
				(width 0.1)
				(type default)
			)
			(layer "B.Fab")
		)
		(fp_line
			(start -0.120396 0.3048)
			(end -0.120396 0.2794)
			(stroke
				(width 0.1)
				(type default)
			)
			(layer "B.Fab")
		)
		(fp_line
			(start -0.67945 0.3048)
			(end -0.120396 0.3048)
			(stroke
				(width 0.1)
				(type default)
			)
			(layer "B.Fab")
		)
		(pad "1" smd circle
			(at 0.40005 0 270)
			(size 0 0)
			(layers "B.Cu" "B.Mask" "B.Paste")
			(net "PWRGD_CHB_CPU0_DIMM2")
		)
		(pad "2" smd circle
			(at -0.40005 0 270)
			(size 0 0)
			(layers "B.Cu" "B.Mask" "B.Paste")
			(net "PWRGD_FAIL_CPU0_AB")
		)
	)
	(footprint ""
		(layer "B.Cu")
		(at 318.223138 -187.90793 -90)
		(property "Reference" "R239"
			(at 0 0 90)
			(layer "B.SilkS")
			(hide yes)
			(effects
				(font
					(size 1.27 1.27)
				)
				(justify mirror)
			)
		)
		(property "Value" ""
			(at 0 0 90)
			(layer "B.Fab")
			(effects
				(font
					(size 1.27 1.27)
				)
				(justify mirror)
			)
		)
		(duplicate_pad_numbers_are_jumpers no)
		(fp_line
			(start -0.7874 0.4064)
			(end 0.7874 0.4064)
			(stroke
				(width 0.1524)
				(type default)
			)
			(layer "B.SilkS")
		)
		(fp_line
			(start 0.7874 0.4064)
			(end 0.7874 -0.4064)
			(stroke
				(width 0.1524)
				(type default)
			)
			(layer "B.SilkS")
		)
		(fp_line
			(start -0.7874 -0.4064)
			(end -0.7874 0.4064)
			(stroke
				(width 0.1524)
				(type default)
			)
			(layer "B.SilkS")
		)
		(fp_line
			(start 0.7874 -0.4064)
			(end -0.7874 -0.4064)
			(stroke
				(width 0.1524)
				(type default)
			)
			(layer "B.SilkS")
		)
		(fp_line
			(start -0.67945 0.3048)
			(end -0.120396 0.3048)
			(stroke
				(width 0.1)
				(type default)
			)
			(layer "B.Fab")
		)
		(fp_line
			(start -0.120396 0.3048)
			(end -0.120396 0.2794)
			(stroke
				(width 0.1)
				(type default)
			)
			(layer "B.Fab")
		)
		(fp_line
			(start 0.12065 0.3048)
			(end 0.67945 0.3048)
			(stroke
				(width 0.1)
				(type default)
			)
			(layer "B.Fab")
		)
		(fp_line
			(start 0.67945 0.3048)
			(end 0.67945 -0.305054)
			(stroke
				(width 0.1)
				(type default)
			)
			(layer "B.Fab")
		)
		(fp_line
			(start -0.120396 0.2794)
			(end 0.12065 0.2794)
			(stroke
				(width 0.1)
				(type default)
			)
			(layer "B.Fab")
		)
		(fp_line
			(start 0.12065 0.2794)
			(end 0.12065 0.3048)
			(stroke
				(width 0.1)
				(type default)
			)
			(layer "B.Fab")
		)
		(fp_line
			(start -0.12065 -0.2794)
			(end -0.12065 -0.3048)
			(stroke
				(width 0.1)
				(type default)
			)
			(layer "B.Fab")
		)
		(fp_line
			(start 0.12065 -0.2794)
			(end -0.12065 -0.2794)
			(stroke
				(width 0.1)
				(type default)
			)
			(layer "B.Fab")
		)
		(fp_line
			(start -0.67945 -0.3048)
			(end -0.67945 0.3048)
			(stroke
				(width 0.1)
				(type default)
			)
			(layer "B.Fab")
		)
		(fp_line
			(start -0.12065 -0.3048)
			(end -0.67945 -0.3048)
			(stroke
				(width 0.1)
				(type default)
			)
			(layer "B.Fab")
		)
		(fp_line
			(start 0.12065 -0.305054)
			(end 0.12065 -0.2794)
			(stroke
				(width 0.1)
				(type default)
			)
			(layer "B.Fab")
		)
		(fp_line
			(start 0.67945 -0.305054)
			(end 0.12065 -0.305054)
			(stroke
				(width 0.1)
				(type default)
			)
			(layer "B.Fab")
		)
		(pad "1" smd circle
			(at 0.40005 0 90)
			(size 0 0)
			(layers "B.Cu" "B.Mask" "B.Paste")
			(net "H_CPU0_PROCHOT_LVC1_R_N")
		)
		(pad "2" smd circle
			(at -0.40005 0 90)
			(size 0 0)
			(layers "B.Cu" "B.Mask" "B.Paste")
			(net "H_CPU0_PROCHOT_LVC1_N")
		)
	)
)
